FILE_TYPE = MULTI_PHYS_TABLE;

PART 'G200_10283_01'
CLASS=IO

{========================================================================================}
:CLS_PN          = JEDEC_TYPE               | ALT_SYMBOLS                | DESCRIPTION                                    | CPN_STATUS ;
{========================================================================================}
 'G200-10283-01' = 'S_M_DIL_2X5_P100_V1'    | '(S_M_DIL_2X5_P100_V1)'    | 'CON, 2 X 5 DUAL ROHS, SMT'                    | ''        
 'G200-11249-01' = 'S_M_H_2X5_S_P100_V2'    | '(S_M_H_2X5_S_P100_V2)'    | 'CON,2 X 5 DUAL ROHS,WITH CAP,SMT'             | 'OBSOLETE'        
 'G200-00114-01' = 'S_M_H_2X5_500X190_P100' | '(S_M_H_2X5_500X190_P100)' | 'CON,10P,5X2,2.54MM,VERT,SMT'                  | 'NFND'        
 'G200-11461-01' = 'S_M_H_2X5_S_P0787_V4'   | '(S_M_H_2X5_S_P0787_V4)'   | 'CON,10PIN,2X5 DUAL,2MM PITCH,HEADER,ROHS,SMT' | ''        
 'G200-11675-01' = 'P_M_H_2X5_S_P100_V7'    | '(P_M_H_2X5_S_P100_V7)'    | 'CON,HEADER,10POS,2X5,2.54MM PITCH,VERT,TH'    | ''        
 'G200-11676-01' = 'S_M_H_2X5_S_P100_V3'    | '(S_M_H_2X5_S_P100_V3)'    | 'CON,HEADER,10POS,2X5,2.54MM PITCH,SMD'        | ''        
 'G200-10426-01' = 'S_M_H_2X5_S_P050_V2'    | '(S_M_H_2X5_S_P050_V2)'    | 'CON,PIN HEADER,2X5P,1.27MM,V/T,SMT'           | ''        
 'G200-12150-01' = 'S_M_H_2X5_S_P0787_V5'   | '(S_M_H_2X5_S_P0787_V5)'   | 'CON,2X5,2.00MM PITCH,H 6.7MM,VT,SMT'          | ''        

END_PART

END.

